# SCM (Grand Teton) — schematic netlist excerpt (pin names and nets, part order shuffled) for the footprints in the layout excerpt that follows; sources: Cadence DE-HDL packaged netlist, KiCad conversion of 12092022_DA0F0TMDCD0_F0T_Management_Board_D_brd_V3_OCP.brd

L8  Q_INDUCTOR  BLM18PG121SN1D/2000MA IND  pkg SMLF  page 16 : \1\ = P1V0_AUX ; \2\ = P1V0_STBY_PLAVDD
R513  Q_RES  33.2 1% CHIP  pkg 0402LF  page 32 : A = JTAG_SCM_TDO ; B = JTAG_SCM_PLD_TDO

(kicad_pcb
	(version 20260206)
	(generator "pcbnew")
	(generator_version "10.0")
	(general
		(thickness 1.6)
		(legacy_teardrops no)
	)
	(paper "A4")
	(title_block
		(title "12092022_DA0F0TMDCD0_F0T_Management_Board_D_brd_V3_OCP.brd")
		(comment 1 "Grand Teton / footprints 9-10 of 1440")
	)
	(layers
		(0 "F.Cu" signal "TOP")
		(4 "In1.Cu" signal "GND")
		(6 "In2.Cu" signal "IN1")
		(8 "In3.Cu" signal "GND1")
		(10 "In4.Cu" signal "IN2")
		(12 "In5.Cu" signal "VCC")
		(14 "In6.Cu" signal "VCC1")
		(16 "In7.Cu" signal "IN3")
		(18 "In8.Cu" signal "GND2")
		(20 "In9.Cu" signal "IN4")
		(22 "In10.Cu" signal "GND3")
		(2 "B.Cu" signal "BOTTOM")
		(9 "F.Adhes" user "F.Adhesive")
		(11 "B.Adhes" user "B.Adhesive")
		(13 "F.Paste" user "Package Geometry/Pastemask Top")
		(15 "B.Paste" user "Package Geometry/Pastemask Bottom")
		(5 "F.SilkS" user "Ref Des/Silkscreen Top")
		(7 "B.SilkS" user "Ref Des/Silkscreen Bottom")
		(1 "F.Mask" user "Board Geometry/Soldermask Top")
		(3 "B.Mask" user "Board Geometry/Soldermask Bottom")
		(17 "Dwgs.User" user "User.Drawings")
		(19 "Cmts.User" user "User.Comments")
		(21 "Eco1.User" user "User.Eco1")
		(23 "Eco2.User" user "User.Eco2")
		(25 "Edge.Cuts" user "Board Geometry/Outline")
		(27 "Margin" user)
		(31 "F.CrtYd" user "Package Geometry/Place Bound Top")
		(29 "B.CrtYd" user "Package Geometry/Place Bound Bottom")
		(35 "F.Fab" user "Ref Des/Assembly Top")
		(33 "B.Fab" user "Ref Des/Assembly Bottom")
	)
	(footprint ""
		(layer "F.Cu")
		(at 69.90588 -25.2349 180)
		(property "Reference" "R513"
			(at 0 0 180)
			(layer "F.SilkS")
			(hide yes)
			(effects
				(font
					(size 1.27 1.27)
				)
			)
		)
		(property "Value" ""
			(at 0 0 180)
			(layer "F.Fab")
			(effects
				(font
					(size 1.27 1.27)
				)
			)
		)
		(duplicate_pad_numbers_are_jumpers no)
		(fp_line
			(start 0.7874 0.4064)
			(end -0.7874 0.4064)
			(stroke
				(width 0.1524)
				(type default)
			)
			(layer "F.SilkS")
		)
		(fp_line
			(start 0.7874 -0.4064)
			(end 0.7874 0.4064)
			(stroke
				(width 0.1524)
				(type default)
			)
			(layer "F.SilkS")
		)
		(fp_line
			(start -0.7874 0.4064)
			(end -0.7874 -0.4064)
			(stroke
				(width 0.1524)
				(type default)
			)
			(layer "F.SilkS")
		)
		(fp_line
			(start -0.7874 -0.4064)
			(end 0.7874 -0.4064)
			(stroke
				(width 0.1524)
				(type default)
			)
			(layer "F.SilkS")
		)
		(fp_line
			(start 0.67945 0.3048)
			(end 0.120396 0.3048)
			(stroke
				(width 0.1)
				(type default)
			)
			(layer "F.Fab")
		)
		(fp_line
			(start 0.67945 -0.3048)
			(end 0.67945 0.3048)
			(stroke
				(width 0.1)
				(type default)
			)
			(layer "F.Fab")
		)
		(fp_line
			(start 0.12065 -0.2794)
			(end 0.12065 -0.3048)
			(stroke
				(width 0.1)
				(type default)
			)
			(layer "F.Fab")
		)
		(fp_line
			(start 0.12065 -0.3048)
			(end 0.67945 -0.3048)
			(stroke
				(width 0.1)
				(type default)
			)
			(layer "F.Fab")
		)
		(fp_line
			(start 0.120396 0.3048)
			(end 0.120396 0.2794)
			(stroke
				(width 0.1)
				(type default)
			)
			(layer "F.Fab")
		)
		(fp_line
			(start 0.120396 0.2794)
			(end -0.12065 0.2794)
			(stroke
				(width 0.1)
				(type default)
			)
			(layer "F.Fab")
		)
		(fp_line
			(start -0.12065 0.3048)
			(end -0.67945 0.3048)
			(stroke
				(width 0.1)
				(type default)
			)
			(layer "F.Fab")
		)
		(fp_line
			(start -0.12065 0.2794)
			(end -0.12065 0.3048)
			(stroke
				(width 0.1)
				(type default)
			)
			(layer "F.Fab")
		)
		(fp_line
			(start -0.12065 -0.2794)
			(end 0.12065 -0.2794)
			(stroke
				(width 0.1)
				(type default)
			)
			(layer "F.Fab")
		)
		(fp_line
			(start -0.12065 -0.305054)
			(end -0.12065 -0.2794)
			(stroke
				(width 0.1)
				(type default)
			)
			(layer "F.Fab")
		)
		(fp_line
			(start -0.67945 0.3048)
			(end -0.67945 -0.305054)
			(stroke
				(width 0.1)
				(type default)
			)
			(layer "F.Fab")
		)
		(fp_line
			(start -0.67945 -0.305054)
			(end -0.12065 -0.305054)
			(stroke
				(width 0.1)
				(type default)
			)
			(layer "F.Fab")
		)
		(pad "1" smd circle
			(at -0.40005 0 180)
			(size 0 0)
			(layers "F.Cu" "F.Mask" "F.Paste")
			(net "JTAG_SCM_TDO")
		)
		(pad "2" smd circle
			(at 0.40005 0 180)
			(size 0 0)
			(layers "F.Cu" "F.Mask" "F.Paste")
			(net "JTAG_SCM_PLD_TDO")
		)
	)
	(footprint ""
		(layer "F.Cu")
		(at 73.941686 -37.523674 180)
		(property "Reference" "L8"
			(at 0 0 180)
			(layer "F.SilkS")
			(hide yes)
			(effects
				(font
					(size 1.27 1.27)
				)
			)
		)
		(property "Value" ""
			(at 0 0 180)
			(layer "F.Fab")
			(effects
				(font
					(size 1.27 1.27)
				)
			)
		)
		(duplicate_pad_numbers_are_jumpers no)
		(fp_line
			(start 1.27 0.5842)
			(end 1.27 -0.5842)
			(stroke
				(width 0.1524)
				(type default)
			)
			(layer "F.SilkS")
		)
		(fp_line
			(start 1.27 0.5842)
			(end -1.27 0.5842)
			(stroke
				(width 0.1524)
				(type default)
			)
			(layer "F.SilkS")
		)
		(fp_line
			(start 0.127 0.5842)
			(end 0.127 -0.5842)
			(stroke
				(width 0.1524)
				(type default)
			)
			(layer "F.SilkS")
		)
		(fp_line
			(start -0.127 0.5842)
			(end -0.127 -0.5842)
			(stroke
				(width 0.1524)
				(type default)
			)
			(layer "F.SilkS")
		)
		(fp_line
			(start -1.27 0.5842)
			(end -1.27 -0.5842)
			(stroke
				(width 0.1524)
				(type default)
			)
			(layer "F.SilkS")
		)
		(fp_line
			(start -1.27 -0.5588)
			(end -1.27 -0.5842)
			(stroke
				(width 0.1524)
				(type default)
			)
			(layer "F.SilkS")
		)
		(fp_line
			(start -1.27 -0.5842)
			(end 1.27 -0.5842)
			(stroke
				(width 0.1524)
				(type default)
			)
			(layer "F.SilkS")
		)
		(fp_line
			(start 1.1938 0.4064)
			(end 0.9144 0.4064)
			(stroke
				(width 0.1)
				(type default)
			)
			(layer "F.Fab")
		)
		(fp_line
			(start 1.1938 -0.406654)
			(end 1.1938 0.4064)
			(stroke
				(width 0.1)
				(type default)
			)
			(layer "F.Fab")
		)
		(fp_line
			(start 0.9144 0.508)
			(end -0.9144 0.508)
			(stroke
				(width 0.1)
				(type default)
			)
			(layer "F.Fab")
		)
		(fp_line
			(start 0.9144 0.4064)
			(end 0.9144 0.508)
			(stroke
				(width 0.1)
				(type default)
			)
			(layer "F.Fab")
		)
		(fp_line
			(start 0.9144 -0.406654)
			(end 1.1938 -0.406654)
			(stroke
				(width 0.1)
				(type default)
			)
			(layer "F.Fab")
		)
		(fp_line
			(start 0.9144 -0.508)
			(end 0.9144 -0.406654)
			(stroke
				(width 0.1)
				(type default)
			)
			(layer "F.Fab")
		)
		(fp_line
			(start -0.9144 0.508)
			(end -0.9144 0.406654)
			(stroke
				(width 0.1)
				(type default)
			)
			(layer "F.Fab")
		)
		(fp_line
			(start -0.9144 0.406654)
			(end -1.194308 0.406654)
			(stroke
				(width 0.1)
				(type default)
			)
			(layer "F.Fab")
		)
		(fp_line
			(start -0.9144 -0.406654)
			(end -0.9144 -0.508)
			(stroke
				(width 0.1)
				(type default)
			)
			(layer "F.Fab")
		)
		(fp_line
			(start -0.9144 -0.508)
			(end 0.9144 -0.508)
			(stroke
				(width 0.1)
				(type default)
			)
			(layer "F.Fab")
		)
		(fp_line
			(start -1.194308 0.406654)
			(end -1.194308 -0.406654)
			(stroke
				(width 0.1)
				(type default)
			)
			(layer "F.Fab")
		)
		(fp_line
			(start -1.194308 -0.406654)
			(end -0.9144 -0.406654)
			(stroke
				(width 0.1)
				(type default)
			)
			(layer "F.Fab")
		)
		(pad "1" smd rect
			(at -0.7366 0 90)
			(size 0.7112 0.8128)
			(layers "F.Cu" "F.Mask" "F.Paste")
			(net "P1V0_AUX")
		)
		(pad "2" smd rect
			(at 0.7366 0 90)
			(size 0.7112 0.8128)
			(layers "F.Cu" "F.Mask" "F.Paste")
			(net "P1V0_STBY_PLAVDD")
		)
	)
)
